FILE_TYPE = MACRO_DRAWING;
SET COLOR_WIRE YELLOW;
SET COLOR_PROP ORANGE;
SET COLOR_DOT WHITE;
SET COLOR_ARC YELLOW;
SET COLOR_BODY GREEN;
SET COLOR_NOTE PURPLE;
SET PROP_DISPLAY VALUE;
SET PAGE_NUMBER P188;
FORCEADD UNIVERSAL_GND..1
(-2925 2800);
FORCEPROP 3 LASTPIN (-2925 2850) SIG_NAME GND\g
J 0
(-2915 2860);
DISPLAY 0.659574 (-2915 2860);
PAINT MONO (-2915 2860);
DISPLAY INVISIBLE (-2915 2860);
FORCEPROP 2 LAST CDS_LIB logical_power
J 0
(-2925 2800);
PAINT MONO (-2925 2800);
DISPLAY INVISIBLE (-2925 2800);
FORCEPROP 1 LAST HDL_POWER GND
J 1
(-2900 2725);
DISPLAY 0.872340 (-2900 2725);
PAINT GREEN (-2900 2725);
DISPLAY INVISIBLE (-2900 2725);
FORCEPROP 1 LAST PATH I20
J 0
(-2850 2800);
DISPLAY 0.872340 (-2850 2800);
PAINT AQUA (-2850 2800);
DISPLAY INVISIBLE (-2850 2800);
FORCEPROP 2 LAST ROOM IO_SLOT
J 1
(-3150 2875);
DISPLAY 0.744681 (-3150 2875);
DISPLAY INVISIBLE (-3150 2875);
FORCEADD Q_RES..2
(-2925 3025);
FORCEPROP 1 LAST PART_NUMBER CS31002FB08
J 0
(-2885 2900);
DISPLAY 0.787234 (-2885 2900);
DISPLAY INVISIBLE (-2885 2900);
FORCEPROP 1 LAST TOLERANCE 1%
J 0
(-2880 3050);
DISPLAY 0.787234 (-2880 3050);
FORCEPROP 1 LAST MATERIAL CHIP
J 0
(-2885 2950);
DISPLAY 0.787234 (-2885 2950);
FORCEPROP 1 LAST WATTAGE 1/16W
J 0
(-2885 3000);
DISPLAY 0.787234 (-2885 3000);
FORCEPROP 1 LAST VALUE 10K
J 0
(-2880 3100);
DISPLAY 0.787234 (-2880 3100);
FORCEPROP 1 LAST PACK_TYPE 0402LF
J 0
(-2885 2850);
DISPLAY 0.787234 (-2885 2850);
FORCEPROP 1 LAST $LOCATION R1299
J 0
(-2880 3150);
DISPLAY 0.978723 (-2880 3150);
FORCEPROP 1 LASTPIN (-2925 3125) $PN 1
J 0
(-2920 3087);
DISPLAY 0.787234 (-2920 3087);
FORCEPROP 1 LASTPIN (-2925 2925) $PN 2
J 0
(-2920 2935);
DISPLAY 0.787234 (-2920 2935);
FORCEPROP 2 LAST CDS_LIB pure_quanta
J 0
(-2925 3025);
PAINT MONO (-2925 3025);
DISPLAY INVISIBLE (-2925 3025);
FORCEPROP 1 LAST PATH I21
J 0
(-2875 3200);
DISPLAY 0.978723 (-2875 3200);
PAINT WHITE (-2875 3200);
DISPLAY INVISIBLE (-2875 3200);
FORCEPROP 1 LAST $LOCATION R1299
J 0
(-2875 3250);
DISPLAY 1.021277 (-2875 3250);
DISPLAY INVISIBLE (-2875 3250);
FORCEPROP 2 LAST CDS_LOCATION R1299
J 0
(-2875 3250);
DISPLAY 1.021277 (-2875 3250);
DISPLAY INVISIBLE (-2875 3250);
FORCEPROP 2 LAST $SEC 1
J 0
(-2875 3250);
DISPLAY 0.680851 (-2875 3250);
PAINT MONO (-2875 3250);
DISPLAY INVISIBLE (-2875 3250);
FORCEPROP 2 LAST CDS_SEC 1
J 0
(-2875 3250);
DISPLAY 1.021277 (-2875 3250);
DISPLAY INVISIBLE (-2875 3250);
FORCEADD Q_RES..2
(-2925 3550);
FORCEPROP 1 LAST PART_NUMBER CS21002FB06
J 0
(-2885 3425);
DISPLAY 0.638298 (-2885 3425);
DISPLAY INVISIBLE (-2885 3425);
FORCEPROP 1 LAST VALUE 1K
J 0
(-2880 3625);
DISPLAY 0.787234 (-2880 3625);
FORCEPROP 1 LAST WATTAGE 1/16W
J 0
(-2885 3525);
DISPLAY 0.787234 (-2885 3525);
FORCEPROP 1 LAST MATERIAL EMPTY
J 0
(-2885 3475);
DISPLAY 0.787234 (-2885 3475);
FORCEPROP 1 LAST PACK_TYPE 0402LF
J 0
(-2885 3375);
DISPLAY 0.787234 (-2885 3375);
FORCEPROP 1 LAST TOLERANCE 1%
J 0
(-2880 3575);
DISPLAY 0.787234 (-2880 3575);
FORCEPROP 1 LAST $LOCATION R1298
J 0
(-2880 3675);
DISPLAY 0.978723 (-2880 3675);
FORCEPROP 1 LASTPIN (-2925 3650) $PN 1
J 0
(-2920 3612);
DISPLAY 0.787234 (-2920 3612);
FORCEPROP 1 LASTPIN (-2925 3450) $PN 2
J 0
(-2920 3460);
DISPLAY 0.787234 (-2920 3460);
FORCEPROP 2 LAST CDS_LIB pure_quanta
J 0
(-2925 3550);
PAINT MONO (-2925 3550);
DISPLAY INVISIBLE (-2925 3550);
FORCEPROP 1 LAST PATH I22
J 0
(-2875 3725);
DISPLAY 0.978723 (-2875 3725);
PAINT WHITE (-2875 3725);
DISPLAY INVISIBLE (-2875 3725);
FORCEPROP 1 LAST $LOCATION R1298
J 0
(-2875 3775);
DISPLAY 1.021277 (-2875 3775);
DISPLAY INVISIBLE (-2875 3775);
FORCEPROP 2 LAST CDS_LOCATION R1298
J 0
(-2875 3775);
DISPLAY 1.021277 (-2875 3775);
DISPLAY INVISIBLE (-2875 3775);
FORCEPROP 2 LAST $SEC 1
J 0
(-2875 3775);
DISPLAY 0.680851 (-2875 3775);
PAINT MONO (-2875 3775);
DISPLAY INVISIBLE (-2875 3775);
FORCEPROP 2 LAST CDS_SEC 1
J 0
(-2875 3775);
DISPLAY 1.021277 (-2875 3775);
DISPLAY INVISIBLE (-2875 3775);
FORCEADD UNIVERSAL_POWER..1
(-2925 3800);
FORCEPROP 3 LASTPIN (-2925 3750) SIG_NAME P1V05_PCH_AUX\g
J 0
(-2915 3760);
DISPLAY 0.659574 (-2915 3760);
PAINT MONO (-2915 3760);
DISPLAY INVISIBLE (-2915 3760);
FORCEPROP 1 LAST HDL_POWER P1V05_PCH_AUX
J 1
(-2925 3850);
DISPLAY 0.872340 (-2925 3850);
PAINT GREEN (-2925 3850);
FORCEPROP 2 LAST CDS_LIB logical_power
J 0
(-2925 3800);
PAINT MONO (-2925 3800);
DISPLAY INVISIBLE (-2925 3800);
FORCEPROP 1 LAST PATH I23
J 0
(-2875 3825);
DISPLAY 0.872340 (-2875 3825);
PAINT AQUA (-2875 3825);
DISPLAY INVISIBLE (-2875 3825);
FORCEADD OFFPAGE..2
(-1675 3250);
FORCEPROP 2 LAST $XR0 184 
J 0
(-1486 3250);
DISPLAY 0.638298 (-1486 3250);
PAINT MONO (-1486 3250);
FORCEPROP 2 LAST CDS_LIB standard
J 0
(-1675 3250);
PAINT MONO (-1675 3250);
DISPLAY INVISIBLE (-1675 3250);
FORCEPROP 1 LAST OFFPAGE TRUE
J 0
(-1350 3125);
DISPLAY 0.872340 (-1350 3125);
DISPLAY INVISIBLE (-1350 3125);
FORCEPROP 1 LAST COMMENT_BODY TRUE
J 0
(-1720 3155);
DISPLAY 0.872340 (-1720 3155);
PAINT GREEN (-1720 3155);
DISPLAY INVISIBLE (-1720 3155);
FORCEPROP 2 LAST PATH I25
J 0
(-1475 3300);
DISPLAY 1.021277 (-1475 3300);
DISPLAY INVISIBLE (-1475 3300);
FORCEADD OFFPAGE..2
(1600 3250);
FORCEPROP 2 LAST $XR0 185 
J 0
(1789 3250);
DISPLAY 0.638298 (1789 3250);
PAINT MONO (1789 3250);
FORCEPROP 2 LAST CDS_LIB standard
J 0
(1600 3250);
PAINT MONO (1600 3250);
DISPLAY INVISIBLE (1600 3250);
FORCEPROP 1 LAST OFFPAGE TRUE
J 0
(1925 3125);
DISPLAY 0.872340 (1925 3125);
DISPLAY INVISIBLE (1925 3125);
FORCEPROP 1 LAST COMMENT_BODY TRUE
J 0
(1555 3155);
DISPLAY 0.872340 (1555 3155);
PAINT GREEN (1555 3155);
DISPLAY INVISIBLE (1555 3155);
FORCEPROP 2 LAST PATH I26
J 0
(1800 3300);
DISPLAY 1.021277 (1800 3300);
DISPLAY INVISIBLE (1800 3300);
FORCEADD UNIVERSAL_GND..1
(-150 2800);
FORCEPROP 3 LASTPIN (-150 2850) SIG_NAME GND\g
J 0
(-140 2860);
DISPLAY 0.659574 (-140 2860);
PAINT MONO (-140 2860);
DISPLAY INVISIBLE (-140 2860);
FORCEPROP 2 LAST CDS_LIB logical_power
J 0
(-150 2800);
PAINT MONO (-150 2800);
DISPLAY INVISIBLE (-150 2800);
FORCEPROP 1 LAST HDL_POWER GND
J 1
(-125 2725);
DISPLAY 0.872340 (-125 2725);
PAINT GREEN (-125 2725);
DISPLAY INVISIBLE (-125 2725);
FORCEPROP 1 LAST PATH I30
J 0
(-75 2800);
DISPLAY 0.872340 (-75 2800);
PAINT AQUA (-75 2800);
DISPLAY INVISIBLE (-75 2800);
FORCEPROP 2 LAST ROOM IO_SLOT
J 1
(-375 2875);
DISPLAY 0.744681 (-375 2875);
DISPLAY INVISIBLE (-375 2875);
FORCEADD Q_RES..2
(-150 3025);
FORCEPROP 1 LAST PART_NUMBER CS31002FB08
J 0
(-110 2900);
DISPLAY 0.787234 (-110 2900);
DISPLAY INVISIBLE (-110 2900);
FORCEPROP 1 LAST TOLERANCE 1%
J 0
(-105 3050);
DISPLAY 0.787234 (-105 3050);
FORCEPROP 1 LAST VALUE 10K
J 0
(-105 3100);
DISPLAY 0.787234 (-105 3100);
FORCEPROP 1 LAST WATTAGE 1/16W
J 0
(-110 3000);
DISPLAY 0.787234 (-110 3000);
FORCEPROP 1 LAST MATERIAL CHIP
J 0
(-110 2950);
DISPLAY 0.787234 (-110 2950);
FORCEPROP 1 LAST PACK_TYPE 0402LF
J 0
(-110 2850);
DISPLAY 0.787234 (-110 2850);
FORCEPROP 1 LAST $LOCATION R1311
J 0
(-105 3150);
DISPLAY 0.978723 (-105 3150);
FORCEPROP 1 LASTPIN (-150 3125) $PN 1
J 0
(-145 3087);
DISPLAY 0.787234 (-145 3087);
FORCEPROP 1 LASTPIN (-150 2925) $PN 2
J 0
(-145 2935);
DISPLAY 0.787234 (-145 2935);
FORCEPROP 2 LAST CDS_LIB pure_quanta
J 0
(-150 3025);
PAINT MONO (-150 3025);
DISPLAY INVISIBLE (-150 3025);
FORCEPROP 1 LAST PATH I31
J 0
(-100 3200);
DISPLAY 0.978723 (-100 3200);
PAINT WHITE (-100 3200);
DISPLAY INVISIBLE (-100 3200);
FORCEPROP 2 LAST CDS_LOCATION R1311
J 0
(-100 3250);
DISPLAY 1.021277 (-100 3250);
DISPLAY INVISIBLE (-100 3250);
FORCEPROP 2 LAST $SEC 1
J 0
(-100 3250);
DISPLAY 0.680851 (-100 3250);
PAINT MONO (-100 3250);
DISPLAY INVISIBLE (-100 3250);
FORCEPROP 2 LAST CDS_SEC 1
J 0
(-100 3250);
DISPLAY 1.021277 (-100 3250);
DISPLAY INVISIBLE (-100 3250);
FORCEADD OFFPAGE..2
(4825 3250);
FORCEPROP 2 LAST $XR0 185 
J 0
(5014 3250);
DISPLAY 0.638298 (5014 3250);
PAINT MONO (5014 3250);
FORCEPROP 2 LAST CDS_LIB standard
J 0
(4825 3250);
PAINT MONO (4825 3250);
DISPLAY INVISIBLE (4825 3250);
FORCEPROP 1 LAST OFFPAGE TRUE
J 0
(5150 3125);
DISPLAY 0.872340 (5150 3125);
DISPLAY INVISIBLE (5150 3125);
FORCEPROP 1 LAST COMMENT_BODY TRUE
J 0
(4780 3155);
DISPLAY 0.872340 (4780 3155);
PAINT GREEN (4780 3155);
DISPLAY INVISIBLE (4780 3155);
FORCEPROP 2 LAST PATH I33
J 0
(5025 3300);
DISPLAY 1.021277 (5025 3300);
DISPLAY INVISIBLE (5025 3300);
FORCEADD Q_RES..2
(3075 3025);
FORCEPROP 1 LAST PART_NUMBER CS31002FB08
J 0
(3115 2900);
DISPLAY 0.787234 (3115 2900);
DISPLAY INVISIBLE (3115 2900);
FORCEPROP 1 LAST VALUE 10K
J 0
(3120 3100);
DISPLAY 0.787234 (3120 3100);
FORCEPROP 1 LAST MATERIAL CHIP
J 0
(3115 2950);
DISPLAY 0.787234 (3115 2950);
FORCEPROP 1 LAST PACK_TYPE 0402LF
J 0
(3115 2850);
DISPLAY 0.787234 (3115 2850);
FORCEPROP 1 LAST TOLERANCE 1%
J 0
(3120 3050);
DISPLAY 0.787234 (3120 3050);
FORCEPROP 1 LAST WATTAGE 1/16W
J 0
(3115 3000);
DISPLAY 0.787234 (3115 3000);
FORCEPROP 1 LAST $LOCATION R1457
J 0
(3120 3150);
DISPLAY 0.978723 (3120 3150);
FORCEPROP 1 LASTPIN (3075 3125) $PN 1
J 0
(3080 3087);
DISPLAY 0.787234 (3080 3087);
FORCEPROP 1 LASTPIN (3075 2925) $PN 2
J 0
(3080 2935);
DISPLAY 0.787234 (3080 2935);
FORCEPROP 2 LAST CDS_LIB pure_quanta
J 0
(3075 3025);
PAINT MONO (3075 3025);
DISPLAY INVISIBLE (3075 3025);
FORCEPROP 1 LAST PATH I36
J 0
(3125 3200);
DISPLAY 0.978723 (3125 3200);
PAINT WHITE (3125 3200);
DISPLAY INVISIBLE (3125 3200);
FORCEPROP 2 LAST CDS_LOCATION R1457
J 0
(3125 3250);
DISPLAY 1.021277 (3125 3250);
DISPLAY INVISIBLE (3125 3250);
FORCEPROP 2 LAST $SEC 1
J 0
(3125 3250);
DISPLAY 0.680851 (3125 3250);
PAINT MONO (3125 3250);
DISPLAY INVISIBLE (3125 3250);
FORCEPROP 2 LAST CDS_SEC 1
J 0
(3125 3250);
DISPLAY 1.021277 (3125 3250);
DISPLAY INVISIBLE (3125 3250);
FORCEADD UNIVERSAL_GND..1
(3075 2800);
FORCEPROP 3 LASTPIN (3075 2850) SIG_NAME GND\g
J 0
(3085 2860);
DISPLAY 0.659574 (3085 2860);
PAINT MONO (3085 2860);
DISPLAY INVISIBLE (3085 2860);
FORCEPROP 2 LAST CDS_LIB logical_power
J 0
(3075 2800);
PAINT MONO (3075 2800);
DISPLAY INVISIBLE (3075 2800);
FORCEPROP 1 LAST HDL_POWER GND
J 1
(3100 2725);
DISPLAY 0.872340 (3100 2725);
PAINT GREEN (3100 2725);
DISPLAY INVISIBLE (3100 2725);
FORCEPROP 1 LAST PATH I37
J 0
(3150 2800);
DISPLAY 0.872340 (3150 2800);
PAINT AQUA (3150 2800);
DISPLAY INVISIBLE (3150 2800);
FORCEPROP 2 LAST ROOM IO_SLOT
J 1
(2850 2875);
DISPLAY 0.744681 (2850 2875);
DISPLAY INVISIBLE (2850 2875);
FORCEADD OFFPAGE..2
(1600 1300);
FORCEPROP 2 LAST $XR0 184 
J 0
(1789 1300);
DISPLAY 0.638298 (1789 1300);
PAINT MONO (1789 1300);
FORCEPROP 2 LAST CDS_LIB standard
J 0
(1600 1300);
PAINT MONO (1600 1300);
DISPLAY INVISIBLE (1600 1300);
FORCEPROP 1 LAST OFFPAGE TRUE
J 0
(1925 1175);
DISPLAY 0.872340 (1925 1175);
DISPLAY INVISIBLE (1925 1175);
FORCEPROP 1 LAST COMMENT_BODY TRUE
J 0
(1555 1205);
DISPLAY 0.872340 (1555 1205);
PAINT GREEN (1555 1205);
DISPLAY INVISIBLE (1555 1205);
FORCEPROP 2 LAST PATH I38
J 0
(1800 1350);
DISPLAY 1.021277 (1800 1350);
DISPLAY INVISIBLE (1800 1350);
FORCEADD UNIVERSAL_POWER..1
(-150 1850);
FORCEPROP 3 LASTPIN (-150 1800) SIG_NAME P3V3_AUX\g
J 0
(-140 1810);
DISPLAY 0.659574 (-140 1810);
PAINT MONO (-140 1810);
DISPLAY INVISIBLE (-140 1810);
FORCEPROP 1 LAST HDL_POWER P3V3_AUX
J 1
(-150 1900);
DISPLAY 0.872340 (-150 1900);
PAINT GREEN (-150 1900);
FORCEPROP 2 LAST CDS_LIB logical_power
J 0
(-150 1850);
PAINT MONO (-150 1850);
DISPLAY INVISIBLE (-150 1850);
FORCEPROP 1 LAST PATH I39
J 0
(-100 1875);
DISPLAY 0.872340 (-100 1875);
PAINT AQUA (-100 1875);
DISPLAY INVISIBLE (-100 1875);
FORCEADD UNIVERSAL_GND..1
(-150 850);
FORCEPROP 3 LASTPIN (-150 900) SIG_NAME GND\g
J 0
(-140 910);
DISPLAY 0.659574 (-140 910);
PAINT MONO (-140 910);
DISPLAY INVISIBLE (-140 910);
FORCEPROP 2 LAST CDS_LIB logical_power
J 0
(-150 850);
PAINT MONO (-150 850);
DISPLAY INVISIBLE (-150 850);
FORCEPROP 1 LAST HDL_POWER GND
J 1
(-125 775);
DISPLAY 0.872340 (-125 775);
PAINT GREEN (-125 775);
DISPLAY INVISIBLE (-125 775);
FORCEPROP 1 LAST PATH I42
J 0
(-75 850);
DISPLAY 0.872340 (-75 850);
PAINT AQUA (-75 850);
DISPLAY INVISIBLE (-75 850);
FORCEPROP 2 LAST ROOM IO_SLOT
J 1
(-375 925);
DISPLAY 0.744681 (-375 925);
DISPLAY INVISIBLE (-375 925);
FORCEADD Q_RES..2
(-150 1075);
FORCEPROP 1 LAST PART_NUMBER CS21002FB06
J 0
(-110 950);
DISPLAY 0.638298 (-110 950);
DISPLAY INVISIBLE (-110 950);
FORCEPROP 1 LAST PACK_TYPE 0402LF
J 0
(-110 900);
DISPLAY 0.638298 (-110 900);
FORCEPROP 1 LAST WATTAGE 1/16W
J 0
(-110 1050);
DISPLAY 0.638298 (-110 1050);
FORCEPROP 1 LAST TOLERANCE 1%
J 0
(-105 1100);
DISPLAY 0.638298 (-105 1100);
FORCEPROP 1 LAST MATERIAL CHIP
J 0
(-110 1000);
DISPLAY 0.638298 (-110 1000);
FORCEPROP 1 LAST VALUE 1K
J 0
(-105 1150);
DISPLAY 0.638298 (-105 1150);
FORCEPROP 1 LAST $LOCATION R1476
J 0
(-105 1200);
DISPLAY 0.638298 (-105 1200);
FORCEPROP 1 LASTPIN (-150 1175) $PN 1
J 0
(-145 1137);
DISPLAY 0.787234 (-145 1137);
FORCEPROP 1 LASTPIN (-150 975) $PN 2
J 0
(-145 985);
DISPLAY 0.787234 (-145 985);
FORCEPROP 2 LAST CDS_LIB pure_quanta
J 0
(-150 1075);
PAINT MONO (-150 1075);
DISPLAY INVISIBLE (-150 1075);
FORCEPROP 1 LAST PATH I43
J 0
(-100 1250);
DISPLAY 0.978723 (-100 1250);
PAINT WHITE (-100 1250);
DISPLAY INVISIBLE (-100 1250);
FORCEPROP 2 LAST CDS_LOCATION R1476
J 0
(-100 1300);
DISPLAY 1.021277 (-100 1300);
DISPLAY INVISIBLE (-100 1300);
FORCEPROP 2 LAST $SEC 1
J 0
(-100 1300);
DISPLAY 0.680851 (-100 1300);
PAINT MONO (-100 1300);
DISPLAY INVISIBLE (-100 1300);
FORCEPROP 2 LAST CDS_SEC 1
J 0
(-100 1300);
DISPLAY 1.021277 (-100 1300);
DISPLAY INVISIBLE (-100 1300);
FORCEADD Q_RES..2
(-150 1600);
FORCEPROP 1 LAST PART_NUMBER CS21002FB06
J 0
(-110 1475);
DISPLAY 0.638298 (-110 1475);
DISPLAY INVISIBLE (-110 1475);
FORCEPROP 1 LAST PACK_TYPE 0402LF
J 0
(-110 1425);
DISPLAY 0.638298 (-110 1425);
FORCEPROP 1 LAST MATERIAL EMPTY
J 0
(-110 1525);
DISPLAY 0.638298 (-110 1525);
PAINT RED (-110 1525);
FORCEPROP 1 LAST WATTAGE 1/16W
J 0
(-110 1575);
DISPLAY 0.638298 (-110 1575);
FORCEPROP 1 LAST VALUE 1K
J 0
(-105 1675);
DISPLAY 0.638298 (-105 1675);
FORCEPROP 1 LAST TOLERANCE 1%
J 0
(-105 1625);
DISPLAY 0.638298 (-105 1625);
FORCEPROP 1 LAST $LOCATION R1475
J 0
(-105 1725);
DISPLAY 0.638298 (-105 1725);
FORCEPROP 1 LASTPIN (-150 1700) $PN 1
J 0
(-145 1662);
DISPLAY 0.787234 (-145 1662);
FORCEPROP 1 LASTPIN (-150 1500) $PN 2
J 0
(-145 1510);
DISPLAY 0.787234 (-145 1510);
FORCEPROP 2 LAST CDS_LIB pure_quanta
J 0
(-150 1600);
PAINT MONO (-150 1600);
DISPLAY INVISIBLE (-150 1600);
FORCEPROP 1 LAST PATH I44
J 0
(-100 1775);
DISPLAY 0.978723 (-100 1775);
PAINT WHITE (-100 1775);
DISPLAY INVISIBLE (-100 1775);
FORCEPROP 2 LAST CDS_LOCATION R1475
J 0
(-100 1825);
DISPLAY 1.021277 (-100 1825);
DISPLAY INVISIBLE (-100 1825);
FORCEPROP 2 LAST $SEC 1
J 0
(-100 1825);
DISPLAY 0.680851 (-100 1825);
PAINT MONO (-100 1825);
DISPLAY INVISIBLE (-100 1825);
FORCEPROP 2 LAST CDS_SEC 1
J 0
(-100 1825);
DISPLAY 1.021277 (-100 1825);
DISPLAY INVISIBLE (-100 1825);
FORCEADD OFFPAGE..2
(4825 1300);
FORCEPROP 2 LAST $XR0 184 
J 0
(5014 1300);
DISPLAY 0.638298 (5014 1300);
PAINT MONO (5014 1300);
FORCEPROP 2 LAST CDS_LIB standard
J 0
(4825 1300);
PAINT MONO (4825 1300);
DISPLAY INVISIBLE (4825 1300);
FORCEPROP 1 LAST OFFPAGE TRUE
J 0
(5150 1175);
DISPLAY 0.872340 (5150 1175);
DISPLAY INVISIBLE (5150 1175);
FORCEPROP 1 LAST COMMENT_BODY TRUE
J 0
(4780 1205);
DISPLAY 0.872340 (4780 1205);
PAINT GREEN (4780 1205);
DISPLAY INVISIBLE (4780 1205);
FORCEPROP 2 LAST PATH I45
J 0
(5025 1350);
DISPLAY 1.021277 (5025 1350);
DISPLAY INVISIBLE (5025 1350);
FORCEADD UNIVERSAL_POWER..1
(3075 1850);
FORCEPROP 3 LASTPIN (3075 1800) SIG_NAME P3V3_AUX\g
J 0
(3085 1810);
DISPLAY 0.659574 (3085 1810);
PAINT MONO (3085 1810);
DISPLAY INVISIBLE (3085 1810);
FORCEPROP 1 LAST HDL_POWER P3V3_AUX
J 1
(3075 1900);
DISPLAY 0.872340 (3075 1900);
PAINT GREEN (3075 1900);
FORCEPROP 2 LAST CDS_LIB logical_power
J 0
(3075 1850);
PAINT MONO (3075 1850);
DISPLAY INVISIBLE (3075 1850);
FORCEPROP 1 LAST PATH I46
J 0
(3125 1875);
DISPLAY 0.872340 (3125 1875);
PAINT AQUA (3125 1875);
DISPLAY INVISIBLE (3125 1875);
FORCEADD Q_RES..2
(3075 1600);
FORCEPROP 1 LAST PART_NUMBER CS21002FB06
J 0
(3115 1475);
DISPLAY 0.638298 (3115 1475);
DISPLAY INVISIBLE (3115 1475);
FORCEPROP 1 LAST WATTAGE 1/16W
J 0
(3115 1575);
DISPLAY 0.638298 (3115 1575);
FORCEPROP 1 LAST VALUE 1K
J 0
(3120 1675);
DISPLAY 0.638298 (3120 1675);
FORCEPROP 1 LAST TOLERANCE 1%
J 0
(3120 1625);
DISPLAY 0.638298 (3120 1625);
FORCEPROP 1 LAST MATERIAL EMPTY
J 0
(3115 1525);
DISPLAY 0.638298 (3115 1525);
PAINT RED (3115 1525);
FORCEPROP 1 LAST PACK_TYPE 0402LF
J 0
(3115 1425);
DISPLAY 0.638298 (3115 1425);
FORCEPROP 1 LAST $LOCATION R1477
J 0
(3120 1725);
DISPLAY 0.638298 (3120 1725);
FORCEPROP 1 LASTPIN (3075 1700) $PN 1
J 0
(3080 1662);
DISPLAY 0.787234 (3080 1662);
FORCEPROP 1 LASTPIN (3075 1500) $PN 2
J 0
(3080 1510);
DISPLAY 0.787234 (3080 1510);
FORCEPROP 2 LAST CDS_LIB pure_quanta
J 0
(3075 1600);
PAINT MONO (3075 1600);
DISPLAY INVISIBLE (3075 1600);
FORCEPROP 1 LAST PATH I47
J 0
(3125 1775);
DISPLAY 0.978723 (3125 1775);
PAINT WHITE (3125 1775);
DISPLAY INVISIBLE (3125 1775);
FORCEPROP 2 LAST CDS_LOCATION R1477
J 0
(3125 1825);
DISPLAY 1.021277 (3125 1825);
DISPLAY INVISIBLE (3125 1825);
FORCEPROP 2 LAST $SEC 1
J 0
(3125 1825);
DISPLAY 0.680851 (3125 1825);
PAINT MONO (3125 1825);
DISPLAY INVISIBLE (3125 1825);
FORCEPROP 2 LAST CDS_SEC 1
J 0
(3125 1825);
DISPLAY 1.021277 (3125 1825);
DISPLAY INVISIBLE (3125 1825);
FORCEADD UNIVERSAL_GND..1
(3075 850);
FORCEPROP 3 LASTPIN (3075 900) SIG_NAME GND\g
J 0
(3085 910);
DISPLAY 0.659574 (3085 910);
PAINT MONO (3085 910);
DISPLAY INVISIBLE (3085 910);
FORCEPROP 2 LAST CDS_LIB logical_power
J 0
(3075 850);
PAINT MONO (3075 850);
DISPLAY INVISIBLE (3075 850);
FORCEPROP 1 LAST HDL_POWER GND
J 1
(3100 775);
DISPLAY 0.872340 (3100 775);
PAINT GREEN (3100 775);
DISPLAY INVISIBLE (3100 775);
FORCEPROP 1 LAST PATH I49
J 0
(3150 850);
DISPLAY 0.872340 (3150 850);
PAINT AQUA (3150 850);
DISPLAY INVISIBLE (3150 850);
FORCEPROP 2 LAST ROOM IO_SLOT
J 1
(2850 925);
DISPLAY 0.744681 (2850 925);
DISPLAY INVISIBLE (2850 925);
FORCEADD Q_RES..2
(3075 1075);
FORCEPROP 1 LAST PART_NUMBER CS31002FB08
J 0
(3115 950);
DISPLAY 0.638298 (3115 950);
DISPLAY INVISIBLE (3115 950);
FORCEPROP 1 LAST VALUE 10K
J 0
(3120 1150);
DISPLAY 0.638298 (3120 1150);
FORCEPROP 1 LAST TOLERANCE 1%
J 0
(3120 1100);
DISPLAY 0.638298 (3120 1100);
FORCEPROP 1 LAST WATTAGE 1/16W
J 0
(3115 1050);
DISPLAY 0.638298 (3115 1050);
FORCEPROP 1 LAST PACK_TYPE 0402LF
J 0
(3115 900);
DISPLAY 0.638298 (3115 900);
FORCEPROP 1 LAST MATERIAL CHIP
J 0
(3115 1000);
DISPLAY 0.638298 (3115 1000);
FORCEPROP 1 LAST $LOCATION R1478
J 0
(3120 1200);
DISPLAY 0.808511 (3120 1200);
FORCEPROP 1 LASTPIN (3075 1175) $PN 1
J 0
(3080 1137);
DISPLAY 0.787234 (3080 1137);
FORCEPROP 1 LASTPIN (3075 975) $PN 2
J 0
(3080 985);
DISPLAY 0.787234 (3080 985);
FORCEPROP 2 LAST CDS_LIB pure_quanta
J 0
(3075 1075);
PAINT MONO (3075 1075);
DISPLAY INVISIBLE (3075 1075);
FORCEPROP 1 LAST PATH I50
J 0
(3125 1250);
DISPLAY 0.978723 (3125 1250);
PAINT WHITE (3125 1250);
DISPLAY INVISIBLE (3125 1250);
FORCEPROP 2 LAST CDS_LOCATION R1478
J 0
(3125 1300);
DISPLAY 1.021277 (3125 1300);
DISPLAY INVISIBLE (3125 1300);
FORCEPROP 2 LAST $SEC 1
J 0
(3125 1300);
DISPLAY 0.680851 (3125 1300);
PAINT MONO (3125 1300);
DISPLAY INVISIBLE (3125 1300);
FORCEPROP 2 LAST CDS_SEC 1
J 0
(3125 1300);
DISPLAY 1.021277 (3125 1300);
DISPLAY INVISIBLE (3125 1300);
FORCEADD OFFPAGE..2
(-1675 1325);
FORCEPROP 2 LAST $XR0 182 
J 0
(-1486 1325);
DISPLAY 0.638298 (-1486 1325);
PAINT MONO (-1486 1325);
FORCEPROP 2 LAST CDS_LIB standard
J 0
(-1675 1325);
PAINT MONO (-1675 1325);
DISPLAY INVISIBLE (-1675 1325);
FORCEPROP 1 LAST OFFPAGE TRUE
J 0
(-1350 1200);
DISPLAY 0.872340 (-1350 1200);
DISPLAY INVISIBLE (-1350 1200);
FORCEPROP 1 LAST COMMENT_BODY TRUE
J 0
(-1720 1230);
DISPLAY 0.872340 (-1720 1230);
PAINT GREEN (-1720 1230);
DISPLAY INVISIBLE (-1720 1230);
FORCEPROP 2 LAST PATH I51
J 0
(-1475 1375);
DISPLAY 1.021277 (-1475 1375);
DISPLAY INVISIBLE (-1475 1375);
FORCEADD UNIVERSAL_POWER..1
(-2925 1875);
FORCEPROP 3 LASTPIN (-2925 1825) SIG_NAME P3V3_AUX\g
J 0
(-2915 1835);
DISPLAY 0.659574 (-2915 1835);
PAINT MONO (-2915 1835);
DISPLAY INVISIBLE (-2915 1835);
FORCEPROP 1 LAST HDL_POWER P3V3_AUX
J 1
(-2925 1925);
DISPLAY 0.872340 (-2925 1925);
PAINT GREEN (-2925 1925);
FORCEPROP 2 LAST CDS_LIB logical_power
J 0
(-2925 1875);
PAINT MONO (-2925 1875);
DISPLAY INVISIBLE (-2925 1875);
FORCEPROP 1 LAST PATH I52
J 0
(-2875 1900);
DISPLAY 0.872340 (-2875 1900);
PAINT AQUA (-2875 1900);
DISPLAY INVISIBLE (-2875 1900);
FORCEADD Q_RES..2
(-2925 1625);
FORCEPROP 1 LAST PART_NUMBER CS25112FB04
J 0
(-2885 1500);
DISPLAY 0.638298 (-2885 1500);
DISPLAY INVISIBLE (-2885 1500);
FORCEPROP 1 LAST TOLERANCE 1%
J 0
(-2880 1650);
DISPLAY 0.638298 (-2880 1650);
FORCEPROP 1 LAST VALUE 5.11K
J 0
(-2880 1700);
DISPLAY 0.638298 (-2880 1700);
FORCEPROP 1 LAST MATERIAL CHIP
J 0
(-2885 1550);
DISPLAY 0.638298 (-2885 1550);
FORCEPROP 1 LAST PACK_TYPE 0402LF
J 0
(-2885 1450);
DISPLAY 0.638298 (-2885 1450);
FORCEPROP 1 LAST WATTAGE 1/16W
J 0
(-2885 1600);
DISPLAY 0.638298 (-2885 1600);
FORCEPROP 1 LAST $LOCATION R3038
J 0
(-2880 1750);
DISPLAY 0.638298 (-2880 1750);
FORCEPROP 1 LASTPIN (-2925 1725) $PN 1
J 0
(-2920 1687);
DISPLAY 0.787234 (-2920 1687);
FORCEPROP 1 LASTPIN (-2925 1525) $PN 2
J 0
(-2920 1535);
DISPLAY 0.787234 (-2920 1535);
FORCEPROP 2 LAST CDS_LIB pure_quanta
J 0
(-2925 1625);
PAINT MONO (-2925 1625);
DISPLAY INVISIBLE (-2925 1625);
FORCEPROP 1 LAST PATH I57
J 0
(-2875 1800);
DISPLAY 0.978723 (-2875 1800);
PAINT WHITE (-2875 1800);
DISPLAY INVISIBLE (-2875 1800);
FORCEPROP 2 LAST CDS_LOCATION R3038
J 0
(-2875 1850);
DISPLAY 1.021277 (-2875 1850);
DISPLAY INVISIBLE (-2875 1850);
FORCEPROP 2 LAST $SEC 1
J 0
(-2875 1850);
DISPLAY 0.680851 (-2875 1850);
PAINT MONO (-2875 1850);
DISPLAY INVISIBLE (-2875 1850);
FORCEPROP 2 LAST CDS_SEC 1
J 0
(-2875 1850);
DISPLAY 1.021277 (-2875 1850);
DISPLAY INVISIBLE (-2875 1850);
FORCEADD OFFPAGE..2
(-1700 -750);
FORCEPROP 2 LAST $XR0 184 
J 0
(-1511 -750);
DISPLAY 0.638298 (-1511 -750);
PAINT MONO (-1511 -750);
FORCEPROP 2 LAST CDS_LIB standard
J 0
(-1700 -750);
PAINT MONO (-1700 -750);
DISPLAY INVISIBLE (-1700 -750);
FORCEPROP 1 LAST OFFPAGE TRUE
J 0
(-1375 -875);
DISPLAY 0.872340 (-1375 -875);
DISPLAY INVISIBLE (-1375 -875);
FORCEPROP 1 LAST COMMENT_BODY TRUE
J 0
(-1745 -845);
DISPLAY 0.872340 (-1745 -845);
PAINT GREEN (-1745 -845);
DISPLAY INVISIBLE (-1745 -845);
FORCEPROP 2 LAST PATH I59
J 0
(-1500 -700);
DISPLAY 1.021277 (-1500 -700);
DISPLAY INVISIBLE (-1500 -700);
FORCEADD UNIVERSAL_POWER..1
(-2950 -200);
FORCEPROP 3 LASTPIN (-2950 -250) SIG_NAME P3V3_AUX\g
J 0
(-2940 -240);
DISPLAY 0.659574 (-2940 -240);
PAINT MONO (-2940 -240);
DISPLAY INVISIBLE (-2940 -240);
FORCEPROP 1 LAST HDL_POWER P3V3_AUX
J 1
(-2950 -150);
DISPLAY 0.872340 (-2950 -150);
PAINT GREEN (-2950 -150);
FORCEPROP 2 LAST CDS_LIB logical_power
J 0
(-2950 -200);
PAINT MONO (-2950 -200);
DISPLAY INVISIBLE (-2950 -200);
FORCEPROP 1 LAST PATH I60
J 0
(-2900 -175);
DISPLAY 0.872340 (-2900 -175);
PAINT AQUA (-2900 -175);
DISPLAY INVISIBLE (-2900 -175);
FORCEADD UNIVERSAL_GND..1
(-2950 -1200);
FORCEPROP 3 LASTPIN (-2950 -1150) SIG_NAME GND\g
J 0
(-2940 -1140);
DISPLAY 0.659574 (-2940 -1140);
PAINT MONO (-2940 -1140);
DISPLAY INVISIBLE (-2940 -1140);
FORCEPROP 2 LAST CDS_LIB logical_power
J 0
(-2950 -1200);
PAINT MONO (-2950 -1200);
DISPLAY INVISIBLE (-2950 -1200);
FORCEPROP 1 LAST HDL_POWER GND
J 1
(-2925 -1275);
DISPLAY 0.872340 (-2925 -1275);
PAINT GREEN (-2925 -1275);
DISPLAY INVISIBLE (-2925 -1275);
FORCEPROP 1 LAST PATH I62
J 0
(-2875 -1200);
DISPLAY 0.872340 (-2875 -1200);
PAINT AQUA (-2875 -1200);
DISPLAY INVISIBLE (-2875 -1200);
FORCEPROP 2 LAST ROOM IO_SLOT
J 1
(-3175 -1125);
DISPLAY 0.744681 (-3175 -1125);
DISPLAY INVISIBLE (-3175 -1125);
FORCEADD Q_RES..2
(-2950 -450);
FORCEPROP 1 LAST PART_NUMBER CS21002FB06
J 0
(-2910 -575);
DISPLAY 0.638298 (-2910 -575);
DISPLAY INVISIBLE (-2910 -575);
FORCEPROP 1 LAST MATERIAL EMPTY
J 0
(-2910 -525);
DISPLAY 0.638298 (-2910 -525);
PAINT RED (-2910 -525);
FORCEPROP 1 LAST TOLERANCE 1%
J 0
(-2905 -425);
DISPLAY 0.638298 (-2905 -425);
FORCEPROP 1 LAST PACK_TYPE 0402LF
J 0
(-2910 -625);
DISPLAY 0.638298 (-2910 -625);
FORCEPROP 1 LAST WATTAGE 1/16W
J 0
(-2910 -475);
DISPLAY 0.638298 (-2910 -475);
FORCEPROP 1 LAST VALUE 1K
J 0
(-2905 -375);
DISPLAY 0.638298 (-2905 -375);
FORCEPROP 1 LAST $LOCATION R1220
J 0
(-2905 -325);
DISPLAY 0.638298 (-2905 -325);
FORCEPROP 1 LASTPIN (-2950 -350) $PN 1
J 0
(-2945 -388);
DISPLAY 0.787234 (-2945 -388);
FORCEPROP 1 LASTPIN (-2950 -550) $PN 2
J 0
(-2945 -540);
DISPLAY 0.787234 (-2945 -540);
FORCEPROP 2 LAST CDS_LIB pure_quanta
J 0
(-2950 -450);
PAINT MONO (-2950 -450);
DISPLAY INVISIBLE (-2950 -450);
FORCEPROP 1 LAST PATH I63
J 0
(-2900 -275);
DISPLAY 0.978723 (-2900 -275);
PAINT WHITE (-2900 -275);
DISPLAY INVISIBLE (-2900 -275);
FORCEPROP 2 LAST CDS_LOCATION R1220
J 0
(-2900 -225);
DISPLAY 1.021277 (-2900 -225);
DISPLAY INVISIBLE (-2900 -225);
FORCEPROP 2 LAST $SEC 1
J 0
(-2900 -225);
DISPLAY 0.680851 (-2900 -225);
PAINT MONO (-2900 -225);
DISPLAY INVISIBLE (-2900 -225);
FORCEPROP 2 LAST CDS_SEC 1
J 0
(-2900 -225);
DISPLAY 1.021277 (-2900 -225);
DISPLAY INVISIBLE (-2900 -225);
FORCEADD Q_RES..2
(-2950 -975);
FORCEPROP 1 LAST PART_NUMBER CS21002FB06
J 0
(-2910 -1100);
DISPLAY 0.638298 (-2910 -1100);
DISPLAY INVISIBLE (-2910 -1100);
FORCEPROP 1 LAST PACK_TYPE 0402LF
J 0
(-2910 -1150);
DISPLAY 0.638298 (-2910 -1150);
FORCEPROP 1 LAST MATERIAL CHIP
J 0
(-2910 -1050);
DISPLAY 0.638298 (-2910 -1050);
FORCEPROP 1 LAST WATTAGE 1/16W
J 0
(-2910 -1000);
DISPLAY 0.638298 (-2910 -1000);
FORCEPROP 1 LAST VALUE 1K
J 0
(-2905 -900);
DISPLAY 0.638298 (-2905 -900);
FORCEPROP 1 LAST TOLERANCE 1%
J 0
(-2905 -950);
DISPLAY 0.638298 (-2905 -950);
FORCEPROP 1 LAST $LOCATION R1221
J 0
(-2905 -850);
DISPLAY 0.638298 (-2905 -850);
FORCEPROP 1 LASTPIN (-2950 -875) $PN 1
J 0
(-2945 -913);
DISPLAY 0.787234 (-2945 -913);
FORCEPROP 1 LASTPIN (-2950 -1075) $PN 2
J 0
(-2945 -1065);
DISPLAY 0.787234 (-2945 -1065);
FORCEPROP 2 LAST CDS_LIB pure_quanta
J 0
(-2950 -975);
PAINT MONO (-2950 -975);
DISPLAY INVISIBLE (-2950 -975);
FORCEPROP 1 LAST PATH I64
J 0
(-2900 -800);
DISPLAY 0.978723 (-2900 -800);
PAINT WHITE (-2900 -800);
DISPLAY INVISIBLE (-2900 -800);
FORCEPROP 2 LAST CDS_LOCATION R1221
J 0
(-2900 -750);
DISPLAY 1.021277 (-2900 -750);
DISPLAY INVISIBLE (-2900 -750);
FORCEPROP 2 LAST $SEC 1
J 0
(-2900 -750);
DISPLAY 0.680851 (-2900 -750);
PAINT MONO (-2900 -750);
DISPLAY INVISIBLE (-2900 -750);
FORCEPROP 2 LAST CDS_SEC 1
J 0
(-2900 -750);
DISPLAY 1.021277 (-2900 -750);
DISPLAY INVISIBLE (-2900 -750);
FORCEADD OFFPAGE..2
(1100 -750);
FORCEPROP 2 LAST $XR0 184 
J 0
(1289 -750);
DISPLAY 0.638298 (1289 -750);
PAINT MONO (1289 -750);
FORCEPROP 2 LAST CDS_LIB standard
J 0
(1100 -750);
PAINT MONO (1100 -750);
DISPLAY INVISIBLE (1100 -750);
FORCEPROP 1 LAST OFFPAGE TRUE
J 0
(1425 -875);
DISPLAY 0.872340 (1425 -875);
DISPLAY INVISIBLE (1425 -875);
FORCEPROP 1 LAST COMMENT_BODY TRUE
J 0
(1055 -845);
DISPLAY 0.872340 (1055 -845);
PAINT GREEN (1055 -845);
DISPLAY INVISIBLE (1055 -845);
FORCEPROP 2 LAST PATH I66
J 0
(1300 -700);
DISPLAY 1.021277 (1300 -700);
DISPLAY INVISIBLE (1300 -700);
FORCEADD UNIVERSAL_POWER..1
(-150 -200);
FORCEPROP 3 LASTPIN (-150 -250) SIG_NAME P3V3_AUX\g
J 0
(-140 -240);
DISPLAY 0.659574 (-140 -240);
PAINT MONO (-140 -240);
DISPLAY INVISIBLE (-140 -240);
FORCEPROP 1 LAST HDL_POWER P3V3_AUX
J 1
(-150 -150);
DISPLAY 0.872340 (-150 -150);
PAINT GREEN (-150 -150);
FORCEPROP 2 LAST CDS_LIB logical_power
J 0
(-150 -200);
PAINT MONO (-150 -200);
DISPLAY INVISIBLE (-150 -200);
FORCEPROP 1 LAST PATH I67
J 0
(-100 -175);
DISPLAY 0.872340 (-100 -175);
PAINT AQUA (-100 -175);
DISPLAY INVISIBLE (-100 -175);
FORCEADD UNIVERSAL_GND..1
(-150 -1200);
FORCEPROP 3 LASTPIN (-150 -1150) SIG_NAME GND\g
J 0
(-140 -1140);
DISPLAY 0.659574 (-140 -1140);
PAINT MONO (-140 -1140);
DISPLAY INVISIBLE (-140 -1140);
FORCEPROP 2 LAST CDS_LIB logical_power
J 0
(-150 -1200);
PAINT MONO (-150 -1200);
DISPLAY INVISIBLE (-150 -1200);
FORCEPROP 1 LAST HDL_POWER GND
J 1
(-125 -1275);
DISPLAY 0.872340 (-125 -1275);
PAINT GREEN (-125 -1275);
DISPLAY INVISIBLE (-125 -1275);
FORCEPROP 1 LAST PATH I69
J 0
(-75 -1200);
DISPLAY 0.872340 (-75 -1200);
PAINT AQUA (-75 -1200);
DISPLAY INVISIBLE (-75 -1200);
FORCEPROP 2 LAST ROOM IO_SLOT
J 1
(-375 -1125);
DISPLAY 0.744681 (-375 -1125);
DISPLAY INVISIBLE (-375 -1125);
FORCEADD Q_RES..2
(-150 -975);
FORCEPROP 1 LAST PART_NUMBER CS31202FB04
J 0
(-110 -1100);
DISPLAY 0.638298 (-110 -1100);
DISPLAY INVISIBLE (-110 -1100);
FORCEPROP 1 LAST TOLERANCE 1%
J 0
(-105 -950);
DISPLAY 0.638298 (-105 -950);
FORCEPROP 1 LAST VALUE 12K
J 0
(-105 -900);
DISPLAY 0.638298 (-105 -900);
FORCEPROP 1 LAST MATERIAL EMPTY
J 0
(-110 -1050);
DISPLAY 0.638298 (-110 -1050);
PAINT RED (-110 -1050);
FORCEPROP 1 LAST PACK_TYPE 0402LF
J 0
(-110 -1150);
DISPLAY 0.638298 (-110 -1150);
FORCEPROP 1 LAST WATTAGE 1/16W
J 0
(-110 -1000);
DISPLAY 0.638298 (-110 -1000);
FORCEPROP 1 LAST $LOCATION R1497
J 0
(-105 -850);
DISPLAY 0.978723 (-105 -850);
FORCEPROP 1 LASTPIN (-150 -875) $PN 1
J 0
(-145 -913);
DISPLAY 0.787234 (-145 -913);
PAINT MONO (-145 -913);
FORCEPROP 1 LASTPIN (-150 -1075) $PN 2
J 0
(-145 -1065);
DISPLAY 0.787234 (-145 -1065);
PAINT MONO (-145 -1065);
FORCEPROP 2 LAST CDS_LIB pure_quanta
J 0
(-150 -975);
DISPLAY INVISIBLE (-150 -975);
FORCEPROP 1 LAST PATH I70
J 0
(-100 -800);
DISPLAY 0.978723 (-100 -800);
PAINT WHITE (-100 -800);
DISPLAY INVISIBLE (-100 -800);
FORCEPROP 2 LAST CDS_LOCATION R1497
J 0
(-100 -750);
DISPLAY 1.021277 (-100 -750);
DISPLAY INVISIBLE (-100 -750);
FORCEPROP 0 LAST $SEC 1
J 0
(-100 -800);
DISPLAY 0.680851 (-100 -800);
PAINT MONO (-100 -800);
DISPLAY INVISIBLE (-100 -800);
FORCEPROP 2 LAST CDS_SEC 1
J 0
(-100 -750);
DISPLAY 1.021277 (-100 -750);
DISPLAY INVISIBLE (-100 -750);
FORCEADD Q_RES..2
(-150 -450);
FORCEPROP 1 LAST PART_NUMBER CS31002FB08
J 0
(-110 -575);
DISPLAY 0.638298 (-110 -575);
DISPLAY INVISIBLE (-110 -575);
FORCEPROP 1 LAST TOLERANCE 1%
J 0
(-105 -425);
DISPLAY 0.638298 (-105 -425);
FORCEPROP 1 LAST PACK_TYPE 0402LF
J 0
(-110 -625);
DISPLAY 0.638298 (-110 -625);
FORCEPROP 1 LAST VALUE 10K
J 0
(-105 -375);
DISPLAY 0.638298 (-105 -375);
FORCEPROP 1 LAST WATTAGE 1/16W
J 0
(-110 -475);
DISPLAY 0.638298 (-110 -475);
FORCEPROP 1 LAST MATERIAL CHIP
J 0
(-110 -525);
DISPLAY 0.638298 (-110 -525);
FORCEPROP 1 LAST $LOCATION R1496
J 0
(-105 -325);
DISPLAY 0.978723 (-105 -325);
FORCEPROP 1 LASTPIN (-150 -350) $PN 1
J 0
(-145 -388);
DISPLAY 0.787234 (-145 -388);
FORCEPROP 1 LASTPIN (-150 -550) $PN 2
J 0
(-145 -540);
DISPLAY 0.787234 (-145 -540);
FORCEPROP 2 LAST CDS_LIB pure_quanta
J 0
(-150 -450);
PAINT MONO (-150 -450);
DISPLAY INVISIBLE (-150 -450);
FORCEPROP 1 LAST PATH I71
J 0
(-100 -275);
DISPLAY 0.978723 (-100 -275);
PAINT WHITE (-100 -275);
DISPLAY INVISIBLE (-100 -275);
FORCEPROP 2 LAST CDS_LOCATION R1496
J 0
(-100 -225);
DISPLAY 1.021277 (-100 -225);
DISPLAY INVISIBLE (-100 -225);
FORCEPROP 2 LAST $SEC 1
J 0
(-100 -225);
DISPLAY 0.680851 (-100 -225);
PAINT MONO (-100 -225);
DISPLAY INVISIBLE (-100 -225);
FORCEPROP 2 LAST CDS_SEC 1
J 0
(-100 -225);
DISPLAY 1.021277 (-100 -225);
DISPLAY INVISIBLE (-100 -225);
FORCEADD OFFPAGE..2
(4825 -750);
FORCEPROP 2 LAST $XR0 184 
J 0
(5014 -750);
DISPLAY 0.638298 (5014 -750);
PAINT MONO (5014 -750);
FORCEPROP 2 LAST CDS_LIB standard
J 0
(4825 -750);
PAINT MONO (4825 -750);
DISPLAY INVISIBLE (4825 -750);
FORCEPROP 1 LAST OFFPAGE TRUE
J 0
(5150 -875);
DISPLAY 0.872340 (5150 -875);
DISPLAY INVISIBLE (5150 -875);
FORCEPROP 1 LAST COMMENT_BODY TRUE
J 0
(4780 -845);
DISPLAY 0.872340 (4780 -845);
PAINT GREEN (4780 -845);
DISPLAY INVISIBLE (4780 -845);
FORCEPROP 2 LAST PATH I72
J 0
(5025 -700);
DISPLAY 1.021277 (5025 -700);
DISPLAY INVISIBLE (5025 -700);
FORCEADD UNIVERSAL_POWER..1
(3075 -200);
FORCEPROP 3 LASTPIN (3075 -250) SIG_NAME P1V05_PCH_AUX\g
J 0
(3085 -240);
DISPLAY 0.659574 (3085 -240);
PAINT MONO (3085 -240);
DISPLAY INVISIBLE (3085 -240);
FORCEPROP 1 LAST HDL_POWER P1V05_PCH_AUX
J 1
(3075 -150);
DISPLAY 0.872340 (3075 -150);
PAINT GREEN (3075 -150);
FORCEPROP 2 LAST CDS_LIB logical_power
J 0
(3075 -200);
PAINT MONO (3075 -200);
DISPLAY INVISIBLE (3075 -200);
FORCEPROP 1 LAST PATH I73
J 0
(3125 -175);
DISPLAY 0.872340 (3125 -175);
PAINT AQUA (3125 -175);
DISPLAY INVISIBLE (3125 -175);
FORCEADD UNIVERSAL_GND..1
(3075 -1200);
FORCEPROP 3 LASTPIN (3075 -1150) SIG_NAME GND\g
J 0
(3085 -1140);
DISPLAY 0.659574 (3085 -1140);
PAINT MONO (3085 -1140);
DISPLAY INVISIBLE (3085 -1140);
FORCEPROP 2 LAST CDS_LIB logical_power
J 0
(3075 -1200);
PAINT MONO (3075 -1200);
DISPLAY INVISIBLE (3075 -1200);
FORCEPROP 1 LAST HDL_POWER GND
J 1
(3100 -1275);
DISPLAY 0.872340 (3100 -1275);
PAINT GREEN (3100 -1275);
DISPLAY INVISIBLE (3100 -1275);
FORCEPROP 1 LAST PATH I75
J 0
(3150 -1200);
DISPLAY 0.872340 (3150 -1200);
PAINT AQUA (3150 -1200);
DISPLAY INVISIBLE (3150 -1200);
FORCEPROP 2 LAST ROOM IO_SLOT
J 1
(2850 -1125);
DISPLAY 0.744681 (2850 -1125);
DISPLAY INVISIBLE (2850 -1125);
FORCEADD Q_RES..2
(3075 -450);
FORCEPROP 1 LAST PART_NUMBER CS21002FB06
J 0
(3115 -575);
DISPLAY 0.638298 (3115 -575);
DISPLAY INVISIBLE (3115 -575);
FORCEPROP 1 LAST TOLERANCE 1%
J 0
(3120 -425);
DISPLAY 0.638298 (3120 -425);
FORCEPROP 1 LAST VALUE 1K
J 0
(3120 -375);
DISPLAY 0.638298 (3120 -375);
FORCEPROP 1 LAST WATTAGE 1/16W
J 0
(3115 -475);
DISPLAY 0.638298 (3115 -475);
FORCEPROP 1 LAST MATERIAL EMPTY
J 0
(3115 -525);
DISPLAY 0.638298 (3115 -525);
PAINT RED (3115 -525);
FORCEPROP 1 LAST PACK_TYPE 0402LF
J 0
(3115 -625);
DISPLAY 0.638298 (3115 -625);
FORCEPROP 1 LAST $LOCATION R1498
J 0
(3120 -325);
DISPLAY 0.978723 (3120 -325);
FORCEPROP 1 LASTPIN (3075 -350) $PN 1
J 0
(3080 -388);
DISPLAY 0.787234 (3080 -388);
FORCEPROP 1 LASTPIN (3075 -550) $PN 2
J 0
(3080 -540);
DISPLAY 0.787234 (3080 -540);
FORCEPROP 2 LAST CDS_LIB pure_quanta
J 0
(3075 -450);
PAINT MONO (3075 -450);
DISPLAY INVISIBLE (3075 -450);
FORCEPROP 1 LAST PATH I76
J 0
(3125 -275);
DISPLAY 0.978723 (3125 -275);
PAINT WHITE (3125 -275);
DISPLAY INVISIBLE (3125 -275);
FORCEPROP 2 LAST CDS_LOCATION R1498
J 0
(3125 -225);
DISPLAY 1.021277 (3125 -225);
DISPLAY INVISIBLE (3125 -225);
FORCEPROP 2 LAST $SEC 1
J 0
(3125 -225);
DISPLAY 0.680851 (3125 -225);
PAINT MONO (3125 -225);
DISPLAY INVISIBLE (3125 -225);
FORCEPROP 2 LAST CDS_SEC 1
J 0
(3125 -225);
DISPLAY 1.021277 (3125 -225);
DISPLAY INVISIBLE (3125 -225);
FORCEADD Q_RES..2
(3075 -975);
FORCEPROP 1 LAST PART_NUMBER CS21002FB06
J 0
(3115 -1100);
DISPLAY 0.638298 (3115 -1100);
DISPLAY INVISIBLE (3115 -1100);
FORCEPROP 1 LAST TOLERANCE 1%
J 0
(3120 -950);
DISPLAY 0.638298 (3120 -950);
FORCEPROP 1 LAST VALUE 1K
J 0
(3120 -900);
DISPLAY 0.638298 (3120 -900);
FORCEPROP 1 LAST PACK_TYPE 0402LF
J 0
(3115 -1150);
DISPLAY 0.638298 (3115 -1150);
FORCEPROP 1 LAST WATTAGE 1/16W
J 0
(3115 -1000);
DISPLAY 0.638298 (3115 -1000);
FORCEPROP 1 LAST MATERIAL CHIP
J 0
(3115 -1050);
DISPLAY 0.638298 (3115 -1050);
FORCEPROP 1 LAST $LOCATION R1499
J 0
(3120 -850);
DISPLAY 0.978723 (3120 -850);
FORCEPROP 1 LASTPIN (3075 -875) $PN 1
J 0
(3080 -913);
DISPLAY 0.787234 (3080 -913);
FORCEPROP 1 LASTPIN (3075 -1075) $PN 2
J 0
(3080 -1065);
DISPLAY 0.787234 (3080 -1065);
FORCEPROP 2 LAST CDS_LIB pure_quanta
J 0
(3075 -975);
PAINT MONO (3075 -975);
DISPLAY INVISIBLE (3075 -975);
FORCEPROP 1 LAST PATH I77
J 0
(3125 -800);
DISPLAY 0.978723 (3125 -800);
PAINT WHITE (3125 -800);
DISPLAY INVISIBLE (3125 -800);
FORCEPROP 2 LAST CDS_LOCATION R1499
J 0
(3125 -750);
DISPLAY 1.021277 (3125 -750);
DISPLAY INVISIBLE (3125 -750);
FORCEPROP 2 LAST $SEC 1
J 0
(3125 -750);
DISPLAY 0.680851 (3125 -750);
PAINT MONO (3125 -750);
DISPLAY INVISIBLE (3125 -750);
FORCEPROP 2 LAST CDS_SEC 1
J 0
(3125 -750);
DISPLAY 1.021277 (3125 -750);
DISPLAY INVISIBLE (3125 -750);
FORCEADD QUANTA_TITLE_BLOCK_C..1
(5625 -1825);
FORCEPROP 0 LAST CDS_CON_LAST_MODIFIED Fri Aug 25 14:03:15 2023
J 0
(3740 -1810);
PAINT MONO (3740 -1810);
DISPLAY INVISIBLE (3740 -1810);
FORCEPROP 2 LAST CUSTOM_TXT_CDS <XR_PAGE_TITLE>
J 0
(-2265 3425);
DISPLAY 0.638298 (-2265 3425);
PAINT PINK (-2265 3425);
DISPLAY INVISIBLE (-2265 3425);
FORCEPROP 2 LAST CUSTOM_TXT_CDS CR-166 : @ES_MB_LIB.ES_MB(SCH_1):PAGE166
J 0
(-2265 3425);
DISPLAY 0.638298 (-2265 3425);
PAINT PINK (-2265 3425);
DISPLAY INVISIBLE (-2265 3425);
FORCEPROP 2 LAST CUSTOM_TXT_CDS <CON_LAST_MODIFIED>
J 0
(3740 -1810);
DISPLAY 0.978723 (3740 -1810);
FORCEPROP 2 LAST CUSTOM_TXT_CDS <Q_NUMBER>
J 0
(4222 -1722);
DISPLAY 1.212766 (4222 -1722);
FORCEPROP 1 LAST CUSTOM_TXT_CDS <NAME_2>
J 0
(2450 -1775);
FORCEPROP 1 LAST CUSTOM_TXT_CDS <NAME_1>
J 0
(2450 -1650);
FORCEPROP 1 LAST CUSTOM_TXT_CDS <Q_PROJ>
J 0
(3243 -1723);
DISPLAY 1.212766 (3243 -1723);
FORCEPROP 1 LAST CUSTOM_TXT_CDS <Q_REV>
J 0
(5441 -1722);
DISPLAY 1.212766 (5441 -1722);
FORCEPROP 1 LAST CUSTOM_TXT_CDS <CON_PAGE_NUM> OF <CON_TOTAL_PAGES>
J 0
(5179 -1807);
DISPLAY 0.978723 (5179 -1807);
FORCEPROP 1 LAST Q_TITLE PCH SIDEBAND: HW STRAPS (3/4)
J 0
(-3716 -1799);
DISPLAY 1.957447 (-3716 -1799);
PAINT GREEN (-3716 -1799);
FORCEPROP 1 LAST Q_DEPT 
J 1
(1862 -1776);
DISPLAY 1.957447 (1862 -1776);
PAINT GREEN (1862 -1776);
FORCEPROP 2 LAST CDS_XR_PAGE_TITLE CR-200 : @S9S_MB_2U_LIB.S9S_MB_2U(SCH_1):PAGE200
J 0
(-2265 3425);
DISPLAY 0.638298 (-2265 3425);
PAINT PINK (-2265 3425);
DISPLAY INVISIBLE (-2265 3425);
FORCEPROP 1 LAST COMMENT_BODY TRUE
J 0
(5637 -1838);
DISPLAY 0.978723 (5637 -1838);
PAINT GREEN (5637 -1838);
DISPLAY INVISIBLE (5637 -1838);
FORCEPROP 2 LAST CDS_LIB pure_quanta
J 0
(5625 -1825);
PAINT MONO (5625 -1825);
DISPLAY INVISIBLE (5625 -1825);
FORCEPROP 1 LAST CDS_LMAN_SYM_OUTLINE -9475,6775,100,-125
J 0
(5625 -1825);
DISPLAY 0.468085 (5625 -1825);
PAINT GREEN (5625 -1825);
DISPLAY INVISIBLE (5625 -1825);
FORCEPROP 2 LAST PAGE_BORDER TRUE
J 0
(-2265 3425);
DISPLAY 0.638298 (-2265 3425);
PAINT PINK (-2265 3425);
DISPLAY INVISIBLE (-2265 3425);
FORCEADD DNS..2
(-2920 3520);
PAINT RED (-2920 3520);
FORCEPROP 2 LAST CDS_LIB mstr_misc
J 0
(-2920 3520);
PAINT MONO (-2920 3520);
DISPLAY INVISIBLE (-2920 3520);
FORCEPROP 1 LAST COMMENT_BODY TRUE
J 0
(-2920 3520);
DISPLAY INVISIBLE (-2920 3520);
FORCEADD DNS..2
(-145 1570);
PAINT RED (-145 1570);
FORCEPROP 2 LAST CDS_LIB mstr_misc
J 0
(-145 1570);
PAINT MONO (-145 1570);
DISPLAY INVISIBLE (-145 1570);
FORCEPROP 1 LAST COMMENT_BODY TRUE
J 0
(-145 1570);
DISPLAY INVISIBLE (-145 1570);
FORCEADD DNS..2
(3080 -480);
PAINT RED (3080 -480);
FORCEPROP 2 LAST CDS_LIB mstr_misc
J 0
(3080 -480);
PAINT MONO (3080 -480);
DISPLAY INVISIBLE (3080 -480);
FORCEPROP 1 LAST COMMENT_BODY TRUE
J 0
(3080 -480);
DISPLAY INVISIBLE (3080 -480);
FORCEADD DNS..2
(-2945 -480);
PAINT RED (-2945 -480);
FORCEPROP 2 LAST CDS_LIB mstr_misc
J 0
(-2945 -480);
PAINT MONO (-2945 -480);
DISPLAY INVISIBLE (-2945 -480);
FORCEPROP 1 LAST COMMENT_BODY TRUE
J 0
(-2945 -480);
DISPLAY INVISIBLE (-2945 -480);
FORCEADD DNS..2
(-145 -980);
PAINT RED (-145 -980);
FORCEPROP 2 LAST CDS_LIB mstr_misc
J 0
(-145 -980);
PAINT MONO (-145 -980);
DISPLAY INVISIBLE (-145 -980);
FORCEPROP 1 LAST COMMENT_BODY TRUE
J 0
(-145 -980);
DISPLAY INVISIBLE (-145 -980);
FORCEADD DNS..2
(3080 1570);
PAINT RED (3080 1570);
FORCEPROP 2 LAST CDS_LIB mstr_misc
J 0
(3080 1570);
PAINT MONO (3080 1570);
DISPLAY INVISIBLE (3080 1570);
FORCEPROP 1 LAST COMMENT_BODY TRUE
J 0
(3080 1570);
DISPLAY INVISIBLE (3080 1570);
WIRE 16 -1 (3075 -350)(3075 -250);
WIRE 16 -1 (-150 -350)(-150 -250);
WIRE 16 -1 (-2950 -350)(-2950 -250);
WIRE 16 -1 (-2925 1725)(-2925 1825);
WIRE 16 -1 (3075 1700)(3075 1800);
WIRE 16 -1 (-150 1700)(-150 1800);
WIRE 16 -1 (-2925 3650)(-2925 3750);
WIRE 16 -1 (3075 -1150)(3075 -1075);
WIRE 16 -1 (-150 -1150)(-150 -1075);
WIRE 16 -1 (-2950 -1150)(-2950 -1075);
WIRE 16 -1 (3075 900)(3075 975);
WIRE 16 -1 (-150 900)(-150 975);
WIRE 16 -1 (3075 2850)(3075 2925);
WIRE 16 -1 (-150 2850)(-150 2925);
WIRE 16 -1 (-2925 2850)(-2925 2925);
WIRE 16 273 (2500 -1375)(2500 4525);
WIRE 16 273 (5300 575)(-3500 575);
WIRE 16 -1 (-2925 1525)(-2925 1325);
WIRE 16 -1 (-2925 1325)(-1725 1325);
FORCEPROP 2 LAST SIG_NAME FM_PCH_SPARE0
J 0
(-2785 1335);
DISPLAY 0.808511 (-2785 1335);
PAINT WHITE (-2785 1335);
WIRE 16 -1 (-2950 -750)(-2950 -875);
WIRE 16 -1 (-2950 -550)(-2950 -750);
WIRE 16 -1 (-2950 -750)(-1750 -750);
FORCEPROP 2 LAST SIG_NAME FM_PCH_MCRO_LDO
J 0
(-2810 -740);
DISPLAY 0.808511 (-2810 -740);
PAINT WHITE (-2810 -740);
WIRE 16 -1 (3075 1300)(3075 1175);
WIRE 16 -1 (3075 1500)(3075 1300);
WIRE 16 -1 (3075 1300)(4775 1300);
FORCEPROP 2 LAST SIG_NAME FM_PCH_XTAL_INPUT_MODE_MGPIO_TEST3
J 0
(3215 1310);
DISPLAY 0.808511 (3215 1310);
PAINT WHITE (3215 1310);
WIRE 16 -1 (-150 1300)(-150 1175);
WIRE 16 -1 (-150 1500)(-150 1300);
WIRE 16 -1 (-150 1300)(1550 1300);
FORCEPROP 2 LAST SIG_NAME FM_PCH_RING_OSC_BYPASS_MGPIO_TEST2
J 0
(-10 1310);
DISPLAY 0.808511 (-10 1310);
PAINT WHITE (-10 1310);
WIRE 16 -1 (3075 -750)(3075 -875);
WIRE 16 -1 (3075 -550)(3075 -750);
WIRE 16 -1 (3075 -750)(4775 -750);
FORCEPROP 2 LAST SIG_NAME FM_BIOS_ADV_FUNCTIONS
J 0
(3215 -740);
DISPLAY 0.808511 (3215 -740);
PAINT WHITE (3215 -740);
WIRE 16 -1 (-2925 3250)(-2925 3125);
WIRE 16 -1 (-2925 3450)(-2925 3250);
WIRE 16 -1 (-2925 3250)(-1725 3250);
FORCEPROP 2 LAST SIG_NAME FM_MFG_MODE
J 0
(-2785 3260);
DISPLAY 0.808511 (-2785 3260);
PAINT WHITE (-2785 3260);
WIRE 16 -1 (3075 3250)(3075 3125);
WIRE 16 -1 (3075 3250)(4775 3250);
FORCEPROP 2 LAST SIG_NAME FM_XTAL_INPUT_FREQUENCY_1_MGPIO_TEST5
J 0
(3215 3260);
DISPLAY 0.808511 (3215 3260);
PAINT WHITE (3215 3260);
WIRE 16 -1 (-150 3250)(-150 3125);
WIRE 16 -1 (-150 3250)(1550 3250);
FORCEPROP 2 LAST SIG_NAME FM_XTAL_INPUT_FREQUENCY_0_MGPIO_TEST4
J 0
(-10 3260);
DISPLAY 0.808511 (-10 3260);
PAINT WHITE (-10 3260);
WIRE 16 -1 (-150 -750)(-150 -875);
WIRE 16 -1 (-150 -550)(-150 -750);
WIRE 16 -1 (-150 -750)(1050 -750);
FORCEPROP 2 LAST SIG_NAME FM_PCH_DFXTESTMODE
J 0
(-10 -740);
DISPLAY 0.808511 (-10 -740);
PAINT WHITE (-10 -740);
WIRE 16 3135 (4150 -225)(4300 -225);
WIRE 16 3135 (4150 -100)(4150 -225);
WIRE 16 3135 (4300 -225)(5375 -225);
WIRE 16 3135 (5375 -225)(5375 -100);
WIRE 16 3135 (4150 25)(4150 -100);
WIRE 16 3135 (4300 -100)(4150 -100);
WIRE 16 3135 (4300 -100)(4300 -225);
WIRE 16 3135 (5375 -100)(4300 -100);
WIRE 16 3135 (4300 25)(4300 -100);
WIRE 16 3135 (4300 25)(4150 25);
WIRE 16 3135 (5375 -100)(5375 25);
WIRE 16 3135 (5375 25)(4300 25);
WIRE 16 273 (-3500 2650)(5300 2650);
WIRE 16 3135 (5325 3900)(5325 4025);
WIRE 16 3135 (5325 4025)(4225 4025);
WIRE 16 3135 (4225 4025)(4075 4025);
WIRE 16 3135 (4225 4025)(4225 3900);
WIRE 16 3135 (5325 3900)(4225 3900);
WIRE 16 3135 (5325 3775)(5325 3900);
WIRE 16 3135 (4075 4025)(4075 3900);
WIRE 16 3135 (4225 3900)(4075 3900);
WIRE 16 3135 (4075 3900)(4075 3775);
WIRE 16 3135 (5325 3525)(5325 3650);
WIRE 16 3135 (5325 3650)(5325 3775);
WIRE 16 3135 (4225 3900)(4225 3775);
WIRE 16 3135 (4225 3775)(5325 3775);
WIRE 16 3135 (4075 3775)(4225 3775);
WIRE 16 3135 (4225 3525)(5325 3525);
WIRE 16 3135 (4075 3525)(4225 3525);
WIRE 16 3135 (4225 3650)(4225 3525);
WIRE 16 3135 (4225 3775)(4225 3650);
WIRE 16 3135 (4225 3650)(5325 3650);
WIRE 16 3135 (4075 3650)(4075 3525);
WIRE 16 3135 (4075 3775)(4075 3650);
WIRE 16 3135 (4075 3650)(4225 3650);
WIRE 16 3135 (925 3650)(925 3525);
WIRE 16 3135 (925 3525)(1075 3525);
WIRE 16 3135 (1075 3525)(2175 3525);
WIRE 16 3135 (925 3650)(1075 3650);
WIRE 16 3135 (1075 3650)(1075 3525);
WIRE 16 3135 (925 3775)(925 3650);
WIRE 16 3135 (925 3900)(925 3775);
WIRE 16 3135 (925 4025)(925 3900);
WIRE 16 3135 (1075 3650)(2175 3650);
WIRE 16 3135 (2175 3525)(2175 3650);
WIRE 16 3135 (925 3775)(1075 3775);
WIRE 16 3135 (1075 3775)(1075 3650);
WIRE 16 3135 (1075 3775)(2175 3775);
WIRE 16 3135 (2175 3650)(2175 3775);
WIRE 16 3135 (1075 3900)(925 3900);
WIRE 16 3135 (1075 3900)(1075 3775);
WIRE 16 3135 (1075 4025)(925 4025);
WIRE 16 3135 (1075 4025)(1075 3900);
WIRE 16 3135 (2175 4025)(1075 4025);
WIRE 16 3135 (2175 3900)(1075 3900);
WIRE 16 3135 (2175 3775)(2175 3900);
WIRE 16 3135 (2175 3900)(2175 4025);
WIRE 16 3135 (925 1950)(925 1825);
WIRE 16 3135 (925 2075)(925 1950);
WIRE 16 3135 (925 1825)(1075 1825);
WIRE 16 3135 (1075 1825)(2175 1825);
WIRE 16 3135 (1075 1950)(925 1950);
WIRE 16 3135 (1075 1950)(1075 1825);
WIRE 16 3135 (1075 2075)(925 2075);
WIRE 16 3135 (1075 2075)(1075 1950);
WIRE 16 3135 (2175 2075)(1075 2075);
WIRE 16 3135 (2175 1950)(1075 1950);
WIRE 16 3135 (2175 1825)(2175 1950);
WIRE 16 3135 (2175 1950)(2175 2075);
WIRE 16 273 (-750 4475)(-750 -1375);
WIRE 16 3135 (4300 1775)(5375 1775);
WIRE 16 3135 (4150 1775)(4300 1775);
WIRE 16 3135 (5375 1775)(5375 1950);
WIRE 16 3135 (5375 1950)(5375 2075);
WIRE 16 3135 (4300 1950)(4300 1775);
WIRE 16 3135 (5375 1950)(4300 1950);
WIRE 16 3135 (4150 1950)(4150 1775);
WIRE 16 3135 (4300 1950)(4150 1950);
WIRE 16 3135 (4150 2075)(4150 1950);
WIRE 16 3135 (4300 2075)(4300 1950);
WIRE 16 3135 (5375 2075)(4300 2075);
WIRE 16 3135 (4300 2075)(4150 2075);
DOT 1 (4225 3900);
DOT 1 (2175 3650);
DOT 1 (2175 1950);
DOT 1 (1075 2075);
DOT 1 (1075 1825);
DOT 1 (1075 1950);
DOT 1 (925 1950);
DOT 1 (4300 2075);
DOT 1 (5375 1950);
DOT 1 (4300 1950);
DOT 1 (4150 1950);
DOT 1 (4300 1775);
DOT 1 (-2950 -750);
DOT 1 (-150 1300);
DOT 1 (2175 3900);
DOT 1 (2175 3775);
DOT 1 (1075 3900);
DOT 1 (1075 4025);
DOT 1 (1075 3775);
DOT 1 (1075 3650);
DOT 1 (1075 3525);
DOT 1 (925 3900);
DOT 1 (925 3775);
DOT 1 (925 3650);
DOT 1 (5325 3900);
DOT 1 (4075 3650);
DOT 1 (4075 3775);
DOT 1 (4075 3900);
DOT 1 (4225 3525);
DOT 1 (4225 3650);
DOT 1 (4225 3775);
DOT 1 (4225 4025);
DOT 1 (5325 3650);
DOT 1 (5325 3775);
DOT 1 (-2925 3250);
DOT 1 (3075 1300);
DOT 1 (4300 -100);
DOT 1 (3075 -750);
DOT 1 (-150 -750);
DOT 1 (4150 -100);
DOT 1 (4300 -225);
DOT 1 (5375 -100);
DOT 1 (4300 25);
FORCENOTE
FUNCTION:RING OSCILLATOR BYPASS
(-560 2319) 0;
DISPLAY LEFT (-560 2319);
DISPLAY 1.276596 (-560 2319);
PAINT YELLOW (-560 2319);
FORCENOTE
PD  RING OSC IS NOT BYPASSED
(975 2000) 0;
DISPLAY LEFT (975 2000);
DISPLAY 0.808511 (975 2000);
PAINT YELLOW (975 2000);
FORCENOTE
PCH INTERNAL:
(2665 2119) 0;
DISPLAY LEFT (2665 2119);
DISPLAY 1.276596 (2665 2119);
PAINT YELLOW (2665 2119);
FORCENOTE
DEFAULT: 0 
(2665 2219) 0;
DISPLAY LEFT (2665 2219);
DISPLAY 1.276596 (2665 2219);
PAINT YELLOW (2665 2219);
FORCENOTE
GROUP: GPPC_H_17
(2665 2419) 0;
DISPLAY LEFT (2665 2419);
DISPLAY 1.276596 (2665 2419);
PAINT YELLOW (2665 2419);
FORCENOTE
01  RESERVED
(4125 3825) 0;
DISPLAY LEFT (4125 3825);
DISPLAY 0.808511 (4125 3825);
PAINT YELLOW (4125 3825);
FORCENOTE
00  25MHZ(SERVER MODE)(DEFAULT)
(4125 3950) 0;
DISPLAY LEFT (4125 3950);
DISPLAY 0.808511 (4125 3950);
PAINT YELLOW (4125 3950);
FORCENOTE
00  25MHZ(SERVER MODE)(DEFAULT)
(975 3950) 0;
DISPLAY LEFT (975 3950);
DISPLAY 0.808511 (975 3950);
PAINT YELLOW (975 3950);
FORCENOTE
FUNCTION:XTAL INPUT MODE
(2665 2319) 0;
DISPLAY LEFT (2665 2319);
DISPLAY 1.276596 (2665 2319);
PAINT YELLOW (2665 2319);
FORCENOTE
PU  RING OSC IS BYPASSED
(975 1875) 0;
DISPLAY LEFT (975 1875);
DISPLAY 0.808511 (975 1875);
PAINT YELLOW (975 1875);
FORCENOTE
PCH INTERNAL:
(-560 2119) 0;
DISPLAY LEFT (-560 2119);
DISPLAY 1.276596 (-560 2119);
PAINT YELLOW (-560 2119);
FORCENOTE
11  100MHZ(BI MODE)
(975 3575) 0;
DISPLAY LEFT (975 3575);
DISPLAY 0.808511 (975 3575);
PAINT YELLOW (975 3575);
FORCENOTE
PCH INTERNAL:
(-560 4069) 0;
DISPLAY LEFT (-560 4069);
DISPLAY 1.276596 (-560 4069);
PAINT YELLOW (-560 4069);
FORCENOTE
DEFAULT: 0 
(-560 4169) 0;
DISPLAY LEFT (-560 4169);
DISPLAY 1.276596 (-560 4169);
PAINT YELLOW (-560 4169);
FORCENOTE
FUNCTION:XTAL_INPUT_FREQUENCY[0]
(-560 4269) 0;
DISPLAY LEFT (-560 4269);
DISPLAY 1.276596 (-560 4269);
PAINT YELLOW (-560 4269);
FORCENOTE
GROUP: GPPC_S_0
(-560 4369) 0;
DISPLAY LEFT (-560 4369);
DISPLAY 1.276596 (-560 4369);
PAINT YELLOW (-560 4369);
FORCENOTE
PCH INTERNAL:
(2665 69) 0;
DISPLAY LEFT (2665 69);
DISPLAY 1.276596 (2665 69);
PAINT YELLOW (2665 69);
FORCENOTE
DEFAULT: 0 
(2665 169) 0;
DISPLAY LEFT (2665 169);
DISPLAY 1.276596 (2665 169);
PAINT YELLOW (2665 169);
FORCENOTE
GROUP: GPPC_L_3
(2665 369) 0;
DISPLAY LEFT (2665 369);
DISPLAY 1.276596 (2665 369);
PAINT YELLOW (2665 369);
FORCENOTE
PCH INTERNAL: NA
(-560 69) 0;
DISPLAY LEFT (-560 69);
DISPLAY 1.276596 (-560 69);
PAINT YELLOW (-560 69);
FORCENOTE
FUNCTION:DFXTESTMODE
(-560 269) 0;
DISPLAY LEFT (-560 269);
DISPLAY 1.276596 (-560 269);
PAINT YELLOW (-560 269);
FORCENOTE
GROUP: GPP_I_22
(-560 369) 0;
DISPLAY LEFT (-560 369);
DISPLAY 1.276596 (-560 369);
PAINT YELLOW (-560 369);
FORCENOTE
PCH INTERNAL: 20K PULL DOWN
(-3335 2144) 0;
DISPLAY LEFT (-3335 2144);
DISPLAY 1.276596 (-3335 2144);
PAINT YELLOW (-3335 2144);
FORCENOTE
DEFAULT: 1 
(-560 169) 0;
DISPLAY LEFT (-560 169);
DISPLAY 1.276596 (-560 169);
PAINT YELLOW (-560 169);
FORCENOTE
FUNCTION:SPARE0
(-3335 2344) 0;
DISPLAY LEFT (-3335 2344);
DISPLAY 1.276596 (-3335 2344);
PAINT YELLOW (-3335 2344);
FORCENOTE
GROUP: GPP_O_0
(-3335 2444) 0;
DISPLAY LEFT (-3335 2444);
DISPLAY 1.276596 (-3335 2444);
PAINT YELLOW (-3335 2444);
FORCENOTE
PD  XTAL IS ATTACHED
(4200 2000) 0;
DISPLAY LEFT (4200 2000);
DISPLAY 0.808511 (4200 2000);
PAINT YELLOW (4200 2000);
FORCENOTE
XTAL IS SINGLE-ENDED
(4350 1875) 0;
DISPLAY LEFT (4350 1875);
DISPLAY 0.808511 (4350 1875);
PAINT YELLOW (4350 1875);
FORCENOTE
CRYSTAL INPUT
(4350 1800) 0;
DISPLAY LEFT (4350 1800);
DISPLAY 0.808511 (4350 1800);
PAINT YELLOW (4350 1800);
FORCENOTE
PU
(4200 1850) 0;
DISPLAY LEFT (4200 1850);
DISPLAY 0.808511 (4200 1850);
PAINT YELLOW (4200 1850);
FORCENOTE
PCH INTERNAL: NA
(-3360 69) 0;
DISPLAY LEFT (-3360 69);
DISPLAY 1.276596 (-3360 69);
PAINT YELLOW (-3360 69);
FORCENOTE
FUNCTION:MCRO_LDO
(-3360 269) 0;
DISPLAY LEFT (-3360 269);
DISPLAY 1.276596 (-3360 269);
PAINT YELLOW (-3360 269);
FORCENOTE
GROUP: GPPC_H_7
(-3360 369) 0;
DISPLAY LEFT (-3360 369);
DISPLAY 1.276596 (-3360 369);
PAINT YELLOW (-3360 369);
FORCENOTE
DEFAULT: 0 
(-3360 169) 0;
DISPLAY LEFT (-3360 169);
DISPLAY 1.276596 (-3360 169);
PAINT YELLOW (-3360 169);
FORCENOTE
DEFAULT: 1 
(-3335 2244) 0;
DISPLAY LEFT (-3335 2244);
DISPLAY 1.276596 (-3335 2244);
PAINT YELLOW (-3335 2244);
FORCENOTE
10  200MHZ(HVM MODE)
(975 3700) 0;
DISPLAY LEFT (975 3700);
DISPLAY 0.808511 (975 3700);
PAINT YELLOW (975 3700);
FORCENOTE
01  RESERVED
(975 3825) 0;
DISPLAY LEFT (975 3825);
DISPLAY 0.808511 (975 3825);
PAINT YELLOW (975 3825);
FORCENOTE
10  200MHZ(HVM MODE)
(4125 3700) 0;
DISPLAY LEFT (4125 3700);
DISPLAY 0.808511 (4125 3700);
PAINT YELLOW (4125 3700);
FORCENOTE
11  100MHZ(BI MODE)
(4125 3575) 0;
DISPLAY LEFT (4125 3575);
DISPLAY 0.808511 (4125 3575);
PAINT YELLOW (4125 3575);
FORCENOTE
PCH INTERNAL:
(2665 4069) 0;
DISPLAY LEFT (2665 4069);
DISPLAY 1.276596 (2665 4069);
PAINT YELLOW (2665 4069);
FORCENOTE
DEFAULT: 0 
(2665 4169) 0;
DISPLAY LEFT (2665 4169);
DISPLAY 1.276596 (2665 4169);
PAINT YELLOW (2665 4169);
FORCENOTE
FUNCTION:XTAL_INPUT_FREQUENCY[1]
(2665 4269) 0;
DISPLAY LEFT (2665 4269);
DISPLAY 1.276596 (2665 4269);
PAINT YELLOW (2665 4269);
FORCENOTE
GROUP: GPPC_S_2
(2665 4369) 0;
DISPLAY LEFT (2665 4369);
DISPLAY 1.276596 (2665 4369);
PAINT YELLOW (2665 4369);
FORCENOTE
PCH INTERNAL: PULL DOWN
(-3335 4069) 0;
DISPLAY LEFT (-3335 4069);
DISPLAY 1.276596 (-3335 4069);
PAINT YELLOW (-3335 4069);
FORCENOTE
GROUP: GPP_L_6
(-3335 4369) 0;
DISPLAY LEFT (-3335 4369);
DISPLAY 1.276596 (-3335 4369);
PAINT YELLOW (-3335 4369);
FORCENOTE
DEFAULT: 0 
(-3335 4169) 0;
DISPLAY LEFT (-3335 4169);
DISPLAY 1.276596 (-3335 4169);
PAINT YELLOW (-3335 4169);
FORCENOTE
FUNCTION:MFG MODE
(-3335 4269) 0;
DISPLAY LEFT (-3335 4269);
DISPLAY 1.276596 (-3335 4269);
PAINT YELLOW (-3335 4269);
FORCENOTE
GROUP: GPPC_H_16
(-560 2419) 0;
DISPLAY LEFT (-560 2419);
DISPLAY 1.276596 (-560 2419);
PAINT YELLOW (-560 2419);
FORCENOTE
DEFAULT: 0 
(-560 2219) 0;
DISPLAY LEFT (-560 2219);
DISPLAY 1.276596 (-560 2219);
PAINT YELLOW (-560 2219);
FORCENOTE
PU  BIOS CORE EXECUTION TREE
(4200 -175) 0;
DISPLAY LEFT (4200 -175);
DISPLAY 0.808511 (4200 -175);
PAINT YELLOW (4200 -175);
FORCENOTE
PD  NORMAL OPERATION (DEFAULT)
(4200 -50) 0;
DISPLAY LEFT (4200 -50);
DISPLAY 0.808511 (4200 -50);
PAINT YELLOW (4200 -50);
FORCENOTE
FUNCTION:BIOS ADVANCE FUNCTIONS
(2665 269) 0;
DISPLAY LEFT (2665 269);
DISPLAY 1.276596 (2665 269);
PAINT YELLOW (2665 269);
QUIT
